#ISCELL
  mstr_misc dns *
  *
#ISCELL
  pure_quanta quanta_title_block_c *
  *
#ISCELL
  standard offpage *
  page365_i1
#CELL
  pure_quanta q_res *
  page365_i10
#ISCELL
  pure_quanta_power universal_power *
  page365_i11
#CELL
  pure_quanta mosfet_nch_gds_esd_protected *
  page365_i14
#ISCELL
  pure_quanta_power universal_gnd *
  page365_i15
#CELL
  pure_quanta 74lvc2g07dw7 *
  page365_i16
#ISCELL
  pure_quanta_power universal_gnd *
  page365_i17
#CELL
  pure_quanta q_res *
  page365_i18
#ISCELL
  standard offpage *
  page365_i19
#CELL
  pure_quanta q_res *
  page365_i20
#ISCELL
  standard offpage *
  page365_i21
#ISCELL
  pure_quanta_power universal_power *
  page365_i22
#CELL
  pure_quanta q_cap *
  page365_i23
#ISCELL
  pure_quanta_power universal_gnd *
  page365_i24
#CELL
  pure_quanta q_cap *
  page365_i25
#ISCELL
  pure_quanta_power universal_gnd *
  page365_i26
#CELL
  pure_quanta q_res *
  page365_i27
#ISCELL
  pure_quanta_power universal_power *
  page365_i28
#CELL
  pure_quanta q_res *
  page365_i3
#ISCELL
  pure_quanta_power universal_power *
  page365_i30
#CELL
  pure_quanta q_res *
  page365_i31
#ISCELL
  pure_quanta_power universal_gnd *
  page365_i5
#CELL
  pure_quanta mosfet_nch_gds_esd_protected *
  page365_i6
#CELL
  pure_quanta q_res *
  page365_i7
#CELL
  pure_quanta q_res *
  page365_i8
#ISCELL
  pure_quanta_power universal_power *
  page365_i9
